#ISCELL
  mstr_misc dns *
  *
#ISCELL
  pure_quanta quanta_title_block_c *
  *
#CELL
  pure_quanta q_res *
  page55_i10
#ISCELL
  pure_quanta_power universal_gnd *
  page55_i11
#CELL
  pure_quanta q_xtal_4p_13bi_24gnd *
  page55_i12
#ISCELL
  standard offpage *
  page55_i126
#ISCELL
  standard offpage *
  page55_i127
#ISCELL
  standard offpage *
  page55_i128
#ISCELL
  standard offpage *
  page55_i129
#ISCELL
  pure_quanta_power universal_gnd *
  page55_i13
#CELL
  pure_quanta q_res *
  page55_i130
#CELL
  pure_quanta q_res *
  page55_i131
#CELL
  pure_quanta q_res *
  page55_i132
#ISCELL
  pure_quanta_power universal_power *
  page55_i133
#CELL
  pure_quanta q_res *
  page55_i134
#CELL
  pure_quanta q_res *
  page55_i139
#ISCELL
  pure_quanta_power universal_gnd *
  page55_i14
#ISCELL
  standard offpage *
  page55_i140
#ISCELL
  standard offpage *
  page55_i141
#CELL
  pure_quanta q_res *
  page55_i142
#CELL
  pure_quanta q_res *
  page55_i143
#ISCELL
  standard offpage *
  page55_i144
#CELL
  pure_quanta q_res *
  page55_i148
#ISCELL
  standard offpage *
  page55_i149
#CELL
  pure_quanta q_cap *
  page55_i15
#ISCELL
  standard offpage *
  page55_i154
#CELL
  pure_quanta q_res *
  page55_i155
#ISCELL
  standard offpage *
  page55_i16
#ISCELL
  standard offpage *
  page55_i163
#ISCELL
  standard offpage *
  page55_i165
#ISCELL
  standard offpage *
  page55_i168
#CELL
  pure_quanta q_res *
  page55_i169
#ISCELL
  standard offpage *
  page55_i17
#ISCELL
  standard offpage *
  page55_i172
#ISCELL
  standard offpage *
  page55_i177
#ISCELL
  standard offpage *
  page55_i18
#ISCELL
  standard offpage *
  page55_i180
#CELL
  pure_quanta genoa_sp5 *
  page55_i182
#ISCELL
  standard offpage *
  page55_i183
#ISCELL
  standard offpage *
  page55_i185
#ISCELL
  standard offpage *
  page55_i186
#ISCELL
  standard offpage *
  page55_i187
#ISCELL
  standard offpage *
  page55_i188
#ISCELL
  standard offpage *
  page55_i189
#ISCELL
  standard offpage *
  page55_i19
#ISCELL
  standard offpage *
  page55_i190
#ISCELL
  standard offpage *
  page55_i191
#ISCELL
  standard offpage *
  page55_i192
#ISCELL
  standard offpage *
  page55_i193
#ISCELL
  pure_quanta_power universal_gnd *
  page55_i2
#ISCELL
  standard offpage *
  page55_i212
#ISCELL
  standard offpage *
  page55_i215
#ISCELL
  standard offpage *
  page55_i216
#ISCELL
  standard offpage *
  page55_i217
#ISCELL
  standard offpage *
  page55_i218
#ISCELL
  standard offpage *
  page55_i219
#ISCELL
  standard offpage *
  page55_i220
#ISCELL
  standard offpage *
  page55_i221
#ISCELL
  standard offpage *
  page55_i230
#ISCELL
  standard offpage *
  page55_i231
#ISCELL
  standard offpage *
  page55_i232
#ISCELL
  standard offpage *
  page55_i233
#ISCELL
  standard offpage *
  page55_i234
#CELL
  pure_quanta q_res *
  page55_i236
#CELL
  pure_quanta q_res *
  page55_i24
#ISCELL
  standard offpage *
  page55_i241
#ISCELL
  standard offpage *
  page55_i242
#ISCELL
  standard offpage *
  page55_i243
#ISCELL
  standard offpage *
  page55_i244
#ISCELL
  standard offpage *
  page55_i245
#ISCELL
  pure_quanta_power vcc_core *
  page55_i246
#CELL
  pure_quanta q_res *
  page55_i247
#CELL
  pure_quanta q_res *
  page55_i248
#CELL
  pure_quanta q_res *
  page55_i249
#CELL
  pure_quanta q_res *
  page55_i250
#ISCELL
  standard offpage *
  page55_i251
#ISCELL
  standard offpage *
  page55_i252
#ISCELL
  standard offpage *
  page55_i253
#ISCELL
  standard offpage *
  page55_i254
#ISCELL
  standard offpage *
  page55_i255
#ISCELL
  standard offpage *
  page55_i256
#ISCELL
  standard offpage *
  page55_i257
#CELL
  pure_quanta q_res *
  page55_i258
#CELL
  pure_quanta q_res *
  page55_i26
#ISCELL
  pure_quanta_power universal_gnd *
  page55_i260
#CELL
  pure_quanta q_res *
  page55_i261
#ISCELL
  pure_quanta_power universal_gnd *
  page55_i263
#ISCELL
  pure_quanta_power universal_power *
  page55_i264
#CELL
  pure_quanta q_res *
  page55_i265
#CELL
  pure_quanta q_res *
  page55_i266
#ISCELL
  standard offpage *
  page55_i267
#ISCELL
  standard offpage *
  page55_i268
#ISCELL
  standard offpage *
  page55_i269
#ISCELL
  standard offpage *
  page55_i27
#ISCELL
  standard offpage *
  page55_i277
#ISCELL
  standard offpage *
  page55_i278
#ISCELL
  standard offpage *
  page55_i279
#ISCELL
  standard offpage *
  page55_i280
#ISCELL
  standard offpage *
  page55_i281
#ISCELL
  standard offpage *
  page55_i282
#CELL
  pure_quanta q_res *
  page55_i283
#CELL
  pure_quanta q_res *
  page55_i284
#CELL
  pure_quanta q_res *
  page55_i285
#CELL
  pure_quanta q_res *
  page55_i286
#CELL
  pure_quanta q_res *
  page55_i287
#CELL
  pure_quanta q_res *
  page55_i288
#CELL
  pure_quanta q_res *
  page55_i289
#CELL
  pure_quanta q_res *
  page55_i290
#ISCELL
  pure_quanta_power universal_power *
  page55_i291
#CELL
  pure_quanta q_res *
  page55_i292
#CELL
  pure_quanta q_res *
  page55_i293
#CELL
  pure_quanta q_res *
  page55_i294
#CELL
  pure_quanta q_res *
  page55_i295
#CELL
  pure_quanta q_res *
  page55_i296
#CELL
  pure_quanta q_res *
  page55_i297
#CELL
  pure_quanta q_res *
  page55_i298
#ISCELL
  standard offpage *
  page55_i299
#CELL
  pure_quanta q_cap *
  page55_i3
#ISCELL
  standard offpage *
  page55_i300
#ISCELL
  standard offpage *
  page55_i301
#ISCELL
  pure_quanta_power universal_gnd *
  page55_i4
#CELL
  pure_quanta q_cap *
  page55_i5
#CELL
  pure_quanta q_res *
  page55_i6
#CELL
  pure_quanta q_crystal *
  page55_i7
#ISCELL
  pure_quanta_power universal_gnd *
  page55_i8
#CELL
  pure_quanta q_cap *
  page55_i9
